# BASEBOARD_FAB2 (Tioga Pass) — schematic netlist excerpt (pin names and nets, part order shuffled) for the footprints in the layout excerpt that follows; sources: Cadence DE-HDL packaged netlist, KiCad conversion of Wiwynn_Tioga_Pass_MB.brd

C5G42  CAP_A  22.0UF 4V 20% X6S  pkg 0603V  page 242 : A = PVDDQ_ABC ; B = GND
R1L33  RES  221 1.0% CHIP  pkg 0402  page 175 : A = FM_BEEP_LED_P ; B = P3V3_STBY
C2L14  CAP_A  0.01UF 25V 10% X7R  pkg 0402V  page 173 : A = SATA6G_PCH_PCIE_UP_SATA_RXN<6> ; B = SATA6G_P6_RX_C_DN

(kicad_pcb
	(version 20260206)
	(generator "pcbnew")
	(generator_version "10.0")
	(general
		(thickness 1.6)
		(legacy_teardrops no)
	)
	(paper "A4")
	(title_block
		(title "Wiwynn_Tioga_Pass_MB.brd")
		(comment 1 "Tioga Pass / footprints 3071-3073 of 4770")
	)
	(layers
		(0 "F.Cu" signal "TOP")
		(4 "In1.Cu" signal "L2GND")
		(6 "In2.Cu" signal "L3")
		(8 "In3.Cu" signal "L4GND")
		(10 "In4.Cu" signal "L5")
		(12 "In5.Cu" signal "L6GND")
		(14 "In6.Cu" signal "L7VCC")
		(16 "In7.Cu" signal "L8VCC")
		(18 "In8.Cu" signal "L9GND")
		(20 "In9.Cu" signal "L10")
		(22 "In10.Cu" signal "L11GND")
		(24 "In11.Cu" signal "L12")
		(26 "In12.Cu" signal "L13GND")
		(2 "B.Cu" signal "BOTTOM")
		(9 "F.Adhes" user "F.Adhesive")
		(11 "B.Adhes" user "B.Adhesive")
		(13 "F.Paste" user "Package Geometry/Pastemask Top")
		(15 "B.Paste" user "Package Geometry/Pastemask Bottom")
		(5 "F.SilkS" user "Ref Des/Silkscreen Top")
		(7 "B.SilkS" user "Ref Des/Silkscreen Bottom")
		(1 "F.Mask" user "Board Geometry/Soldermask Top")
		(3 "B.Mask" user "Board Geometry/Soldermask Bottom")
		(17 "Dwgs.User" user "User.Drawings")
		(19 "Cmts.User" user "User.Comments")
		(21 "Eco1.User" user "User.Eco1")
		(23 "Eco2.User" user "User.Eco2")
		(25 "Edge.Cuts" user "Board Geometry/Outline")
		(27 "Margin" user)
		(31 "F.CrtYd" user "Package Geometry/Place Bound Top")
		(29 "B.CrtYd" user "Package Geometry/Place Bound Bottom")
		(35 "F.Fab" user "Ref Des/Assembly Top")
		(33 "B.Fab" user "Ref Des/Assembly Bottom")
	)
	(footprint ""
		(layer "B.Cu")
		(at 499.3894 -140.843)
		(property "Reference" "R1L33"
			(at 0 0 0)
			(layer "B.SilkS")
			(hide yes)
			(effects
				(font
					(size 1.27 1.27)
				)
				(justify mirror)
			)
		)
		(property "Value" ""
			(at 0 0 0)
			(layer "B.Fab")
			(effects
				(font
					(size 1.27 1.27)
				)
				(justify mirror)
			)
		)
		(duplicate_pad_numbers_are_jumpers no)
		(fp_poly
			(pts
				(xy 0.2794 -0.1016) (xy -0.2794 -0.1016) (xy -0.2794 0.9906) (xy 0.2794 0.9906)
			)
			(stroke
				(width 0)
				(type default)
			)
			(fill no)
			(layer "B.CrtYd")
		)
		(fp_line
			(start -0.2794 -0.1016)
			(end 0.2794 -0.1016)
			(stroke
				(width 0.1)
				(type default)
			)
			(layer "B.Fab")
		)
		(fp_line
			(start -0.2794 0.9906)
			(end -0.2794 -0.1016)
			(stroke
				(width 0.1)
				(type default)
			)
			(layer "B.Fab")
		)
		(fp_line
			(start 0.2794 -0.1016)
			(end 0.2794 0.9906)
			(stroke
				(width 0.1)
				(type default)
			)
			(layer "B.Fab")
		)
		(fp_line
			(start 0.2794 0.9906)
			(end -0.2794 0.9906)
			(stroke
				(width 0.1)
				(type default)
			)
			(layer "B.Fab")
		)
		(pad "1" smd rect
			(at 0 0 180)
			(size 0.508 0.508)
			(layers "B.Cu" "B.Mask" "B.Paste")
			(net "FM_BEEP_LED_P")
		)
		(pad "2" smd rect
			(at 0 0.889 180)
			(size 0.508 0.508)
			(layers "B.Cu" "B.Mask" "B.Paste")
			(net "P3V3_STBY")
		)
		(zone
			(layer "B.Cu")
			(hatch none 0.5)
			(connect_pads
				(clearance 0)
			)
			(min_thickness 0.25)
			(keepout
				(tracks allowed)
				(vias not_allowed)
				(pads allowed)
				(copperpour not_allowed)
				(footprints allowed)
			)
			(placement
				(enabled no)
				(sheetname "")
			)
			(fill
				(thermal_gap 0.5)
				(thermal_bridge_width 0.5)
				(island_removal_mode 0)
			)
			(polygon
				(pts
					(xy 499.6434 -140.589) (xy 499.1354 -140.589) (xy 499.1354 -140.208) (xy 499.6434 -140.208)
				)
			)
		)
		(zone
			(layer "B.Cu")
			(hatch none 0.5)
			(connect_pads
				(clearance 0)
			)
			(min_thickness 0.25)
			(keepout
				(tracks not_allowed)
				(vias allowed)
				(pads allowed)
				(copperpour not_allowed)
				(footprints allowed)
			)
			(placement
				(enabled no)
				(sheetname "")
			)
			(fill
				(thermal_gap 0.5)
				(thermal_bridge_width 0.5)
				(island_removal_mode 0)
			)
			(polygon
				(pts
					(xy 499.6434 -140.208) (xy 499.1354 -140.208) (xy 499.1354 -140.589) (xy 499.6434 -140.589)
				)
			)
		)
	)
	(footprint ""
		(layer "B.Cu")
		(at 248.8565 -12.954 -90)
		(property "Reference" "C5G42"
			(at -1.14681 0.76708 0)
			(unlocked yes)
			(layer "B.SilkS")
			(effects
				(font
					(size 0.7874 0.5842)
					(thickness 0.1524)
				)
				(justify mirror)
			)
		)
		(property "Value" ""
			(at 0 0 90)
			(layer "B.Fab")
			(effects
				(font
					(size 1.27 1.27)
				)
				(justify mirror)
			)
		)
		(duplicate_pad_numbers_are_jumpers no)
		(fp_rect
			(start 0.4953 1.6002)
			(end -0.4953 -0.2032)
			(stroke
				(width 0)
				(type default)
			)
			(fill no)
			(layer "B.CrtYd")
		)
		(fp_line
			(start -0.4953 1.6002)
			(end 0.4953 1.6002)
			(stroke
				(width 0.1)
				(type default)
			)
			(layer "B.Fab")
		)
		(fp_line
			(start 0.4953 1.6002)
			(end 0.4953 -0.2032)
			(stroke
				(width 0.1)
				(type default)
			)
			(layer "B.Fab")
		)
		(fp_line
			(start -0.4953 -0.2032)
			(end -0.4953 1.6002)
			(stroke
				(width 0.1)
				(type default)
			)
			(layer "B.Fab")
		)
		(fp_line
			(start 0.4953 -0.2032)
			(end -0.4953 -0.2032)
			(stroke
				(width 0.1)
				(type default)
			)
			(layer "B.Fab")
		)
		(pad "1" smd rect
			(at 0 0 90)
			(size 0.762 0.889)
			(layers "B.Cu" "B.Mask" "B.Paste")
			(net "PVDDQ_ABC")
		)
		(pad "2" smd rect
			(at 0 1.397 90)
			(size 0.762 0.889)
			(layers "B.Cu" "B.Mask" "B.Paste")
			(net "GND")
		)
		(zone
			(layer "B.Cu")
			(hatch none 0.5)
			(connect_pads
				(clearance 0)
			)
			(min_thickness 0.25)
			(keepout
				(tracks not_allowed)
				(vias allowed)
				(pads allowed)
				(copperpour not_allowed)
				(footprints allowed)
			)
			(placement
				(enabled no)
				(sheetname "")
			)
			(fill
				(thermal_gap 0.5)
				(thermal_bridge_width 0.5)
				(island_removal_mode 0)
			)
			(polygon
				(pts
					(xy 247.904 -12.573) (xy 248.412 -12.573) (xy 248.412 -13.335) (xy 247.904 -13.335)
				)
			)
		)
	)
	(footprint ""
		(layer "B.Cu")
		(at 408.305 -151.511 90)
		(property "Reference" "C2L14"
			(at 0 0 90)
			(layer "B.SilkS")
			(hide yes)
			(effects
				(font
					(size 1.27 1.27)
				)
				(justify mirror)
			)
		)
		(property "Value" ""
			(at 0 0 90)
			(layer "B.Fab")
			(effects
				(font
					(size 1.27 1.27)
				)
				(justify mirror)
			)
		)
		(duplicate_pad_numbers_are_jumpers no)
		(fp_poly
			(pts
				(xy -0.3048 -0.1016) (xy -0.3048 0.9906) (xy 0.3048 0.9906) (xy 0.3048 -0.1016)
			)
			(stroke
				(width 0)
				(type default)
			)
			(fill no)
			(layer "B.CrtYd")
		)
		(fp_line
			(start 0.3048 -0.1016)
			(end 0.3048 0.9906)
			(stroke
				(width 0.1)
				(type default)
			)
			(layer "B.Fab")
		)
		(fp_line
			(start -0.3048 -0.1016)
			(end 0.3048 -0.1016)
			(stroke
				(width 0.1)
				(type default)
			)
			(layer "B.Fab")
		)
		(fp_line
			(start 0.3048 0.9906)
			(end -0.3048 0.9906)
			(stroke
				(width 0.1)
				(type default)
			)
			(layer "B.Fab")
		)
		(fp_line
			(start -0.3048 0.9906)
			(end -0.3048 -0.1016)
			(stroke
				(width 0.1)
				(type default)
			)
			(layer "B.Fab")
		)
		(pad "1" smd rect
			(at 0 0 270)
			(size 0.508 0.508)
			(layers "B.Cu" "B.Mask" "B.Paste")
			(net "SATA6G_PCH_PCIE_UP_SATA_RXN<6>")
		)
		(pad "2" smd rect
			(at 0 0.889 270)
			(size 0.508 0.508)
			(layers "B.Cu" "B.Mask" "B.Paste")
			(net "SATA6G_P6_RX_C_DN")
		)
		(zone
			(layer "B.Cu")
			(hatch none 0.5)
			(connect_pads
				(clearance 0)
			)
			(min_thickness 0.25)
			(keepout
				(tracks allowed)
				(vias not_allowed)
				(pads allowed)
				(copperpour not_allowed)
				(footprints allowed)
			)
			(placement
				(enabled no)
				(sheetname "")
			)
			(fill
				(thermal_gap 0.5)
				(thermal_bridge_width 0.5)
				(island_removal_mode 0)
			)
			(polygon
				(pts
					(xy 408.559 -151.765) (xy 408.559 -151.257) (xy 408.94 -151.257) (xy 408.94 -151.765)
				)
			)
		)
		(zone
			(layer "B.Cu")
			(hatch none 0.5)
			(connect_pads
				(clearance 0)
			)
			(min_thickness 0.25)
			(keepout
				(tracks not_allowed)
				(vias allowed)
				(pads allowed)
				(copperpour not_allowed)
				(footprints allowed)
			)
			(placement
				(enabled no)
				(sheetname "")
			)
			(fill
				(thermal_gap 0.5)
				(thermal_bridge_width 0.5)
				(island_removal_mode 0)
			)
			(polygon
				(pts
					(xy 408.94 -151.765) (xy 408.94 -151.257) (xy 408.559 -151.257) (xy 408.559 -151.765)
				)
			)
		)
	)
)
